(kicad_pcb
	(version 20260206)
	(generator "pcbnew")
	(generator_version "10.0")
	(general
		(thickness 1.6)
		(legacy_teardrops no)
	)
	(paper "A4")
	(title_block
		(title "Bryce Canyon_R.DPB_16317-1_OCP.brd")
		(comment 1 "Bryce Canyon / footprints 641-648 of 2099")
	)
	(layers
		(0 "F.Cu" signal "TOP")
		(4 "In1.Cu" signal "L2GND")
		(6 "In2.Cu" signal "L3")
		(8 "In3.Cu" signal "L4VCC")
		(10 "In4.Cu" signal "L5VCC")
		(12 "In5.Cu" signal "L6")
		(14 "In6.Cu" signal "L7GND")
		(2 "B.Cu" signal "BOTTOM")
		(9 "F.Adhes" user "F.Adhesive")
		(11 "B.Adhes" user "B.Adhesive")
		(13 "F.Paste" user "Package Geometry/Pastemask Top")
		(15 "B.Paste" user "Package Geometry/Pastemask Bottom")
		(5 "F.SilkS" user "Ref Des/Silkscreen Top")
		(7 "B.SilkS" user "Ref Des/Silkscreen Bottom")
		(1 "F.Mask" user "Board Geometry/Soldermask Top")
		(3 "B.Mask" user "Board Geometry/Soldermask Bottom")
		(17 "Dwgs.User" user "User.Drawings")
		(19 "Cmts.User" user "User.Comments")
		(21 "Eco1.User" user "User.Eco1")
		(23 "Eco2.User" user "User.Eco2")
		(25 "Edge.Cuts" user "Board Geometry/Outline")
		(27 "Margin" user)
		(31 "F.CrtYd" user "Package Geometry/Place Bound Top")
		(29 "B.CrtYd" user "Package Geometry/Place Bound Bottom")
		(35 "F.Fab" user "Ref Des/Assembly Top")
		(33 "B.Fab" user "Ref Des/Assembly Bottom")
	)
	(footprint ""
		(layer "F.Cu")
		(at 232.55732 -219.04198)
		(property "Reference" "R63"
			(at 0 0 0)
			(layer "F.SilkS")
			(hide yes)
			(effects
				(font
					(size 1.27 1.27)
				)
			)
		)
		(property "Value" "4K7R2F-GP"
			(at 0.064008 -3.993896 0)
			(unlocked yes)
			(layer "F.Fab")
			(hide yes)
			(effects
				(font
					(size 1.016 1.016)
					(thickness 0.1524)
				)
			)
		)
		(property "Device Type" "R402H16"
			(at 0.064008 -5.517896 0)
			(unlocked yes)
			(layer "F.Fab")
			(hide yes)
			(effects
				(font
					(size 1.016 1.016)
					(thickness 0.1524)
				)
			)
		)
		(duplicate_pad_numbers_are_jumpers no)
		(fp_line
			(start -0.508 -0.9398)
			(end -0.508 0.9398)
			(stroke
				(width 0.1524)
				(type default)
			)
			(layer "F.SilkS")
		)
		(fp_line
			(start 0.508 -0.9398)
			(end -0.508 -0.9398)
			(stroke
				(width 0.1524)
				(type default)
			)
			(layer "F.SilkS")
		)
		(fp_rect
			(start -0.508 0.9398)
			(end 0.508 -0.9398)
			(stroke
				(width 0)
				(type default)
			)
			(fill no)
			(layer "F.CrtYd")
		)
		(fp_rect
			(start -0.508 0.9398)
			(end 0.508 -0.9398)
			(stroke
				(width 0)
				(type default)
			)
			(fill no)
			(layer "F.Fab")
		)
		(pad "1" smd custom
			(at 0 -0.4445)
			(size 0.1397 0.1397)
			(layers "F.Cu" "F.Mask" "F.Paste")
			(net "IO_EXP1_A0")
			(options
				(clearance outline)
				(anchor circle)
			)
			(primitives
				(gr_poly
					(pts
						(arc
							(start -0.1778 -0.2794)
							(mid -0.249642 -0.249642)
							(end -0.2794 -0.1778)
						)
						(arc
							(start -0.2794 0.1778)
							(mid -0.249642 0.249642)
							(end -0.1778 0.2794)
						)
						(arc
							(start 0.1778 0.2794)
							(mid 0.249642 0.249642)
							(end 0.2794 0.1778)
						)
						(arc
							(start 0.2794 -0.1778)
							(mid 0.249642 -0.249642)
							(end 0.1778 -0.2794)
						)
					)
					(width 0)
					(fill yes)
				)
			)
		)
		(pad "2" smd custom
			(at 0 0.4445)
			(size 0.1397 0.1397)
			(layers "F.Cu" "F.Mask" "F.Paste")
			(net "GND")
			(options
				(clearance outline)
				(anchor circle)
			)
			(primitives
				(gr_poly
					(pts
						(arc
							(start -0.1778 -0.2794)
							(mid -0.249642 -0.249642)
							(end -0.2794 -0.1778)
						)
						(arc
							(start -0.2794 0.1778)
							(mid -0.249642 0.249642)
							(end -0.1778 0.2794)
						)
						(arc
							(start 0.1778 0.2794)
							(mid 0.249642 0.249642)
							(end 0.2794 0.1778)
						)
						(arc
							(start 0.2794 -0.1778)
							(mid 0.249642 -0.249642)
							(end 0.1778 -0.2794)
						)
					)
					(width 0)
					(fill yes)
				)
			)
		)
	)
	(footprint ""
		(layer "F.Cu")
		(at 384.734562 -14.660626 -90)
		(property "Reference" "C445"
			(at 0 0 270)
			(layer "F.SilkS")
			(hide yes)
			(effects
				(font
					(size 1.27 1.27)
				)
			)
		)
		(property "Value" "SCD01U16V1KX-GP"
			(at -2.8321 -1.7399 270)
			(unlocked yes)
			(layer "F.Fab")
			(hide yes)
			(effects
				(font
					(size 1.016 1.016)
					(thickness 0.1524)
				)
			)
		)
		(property "Device Type" "C0201H13"
			(at -2.8321 -3.2639 270)
			(unlocked yes)
			(layer "F.Fab")
			(hide yes)
			(effects
				(font
					(size 1.016 1.016)
					(thickness 0.1524)
				)
			)
		)
		(duplicate_pad_numbers_are_jumpers no)
		(fp_rect
			(start -0.2794 0.6477)
			(end 0.2794 -0.6477)
			(stroke
				(width 0)
				(type default)
			)
			(fill no)
			(layer "F.CrtYd")
		)
		(fp_rect
			(start -0.2794 0.6477)
			(end 0.2794 -0.6477)
			(stroke
				(width 0)
				(type default)
			)
			(fill no)
			(layer "F.Fab")
		)
		(pad "1" smd custom
			(at 0 -0.2794 270)
			(size 0.0762 0.0762)
			(layers "F.Cu" "F.Mask" "F.Paste")
			(net "SAS_HDD_RX_P32")
			(options
				(clearance outline)
				(anchor circle)
			)
			(primitives
				(gr_poly
					(pts
						(arc
							(start 0.1524 -0.127)
							(mid 0.137521 -0.162921)
							(end 0.1016 -0.1778)
						)
						(arc
							(start -0.1016 -0.1778)
							(mid -0.137521 -0.162921)
							(end -0.1524 -0.127)
						)
						(arc
							(start -0.1524 0.127)
							(mid -0.137521 0.162921)
							(end -0.1016 0.1778)
						)
						(arc
							(start 0.1016 0.1778)
							(mid 0.137521 0.162921)
							(end 0.1524 0.127)
						)
					)
					(width 0)
					(fill yes)
				)
			)
		)
		(pad "2" smd custom
			(at 0 0.2794 270)
			(size 0.0762 0.0762)
			(layers "F.Cu" "F.Mask" "F.Paste")
			(net "PHY_SCC_B_TO_DRV_B_32_DP")
			(options
				(clearance outline)
				(anchor circle)
			)
			(primitives
				(gr_poly
					(pts
						(arc
							(start 0.1524 -0.127)
							(mid 0.137521 -0.162921)
							(end 0.1016 -0.1778)
						)
						(arc
							(start -0.1016 -0.1778)
							(mid -0.137521 -0.162921)
							(end -0.1524 -0.127)
						)
						(arc
							(start -0.1524 0.127)
							(mid -0.137521 0.162921)
							(end -0.1016 0.1778)
						)
						(arc
							(start 0.1016 0.1778)
							(mid 0.137521 0.162921)
							(end 0.1524 0.127)
						)
					)
					(width 0)
					(fill yes)
				)
			)
		)
	)
	(footprint ""
		(layer "F.Cu")
		(at 333.502 -44.958 180)
		(property "Reference" "C425"
			(at 0 0 180)
			(layer "F.SilkS")
			(hide yes)
			(effects
				(font
					(size 1.27 1.27)
				)
			)
		)
		(property "Value" "SC4D7U25V5KX-1-GP"
			(at -0.0762 -6.1214 180)
			(unlocked yes)
			(layer "F.Fab")
			(hide yes)
			(effects
				(font
					(size 1.016 1.016)
					(thickness 0.1524)
				)
			)
		)
		(property "Device Type" "C805H58"
			(at -0.0762 -8.1534 180)
			(unlocked yes)
			(layer "F.Fab")
			(hide yes)
			(effects
				(font
					(size 1.016 1.016)
					(thickness 0.1524)
				)
			)
		)
		(duplicate_pad_numbers_are_jumpers no)
		(fp_line
			(start 0.635 0)
			(end -0.635 0)
			(stroke
				(width 0.508)
				(type default)
			)
			(layer "F.SilkS")
		)
		(fp_rect
			(start -0.9652 1.778)
			(end 0.9652 -1.778)
			(stroke
				(width 0)
				(type default)
			)
			(fill no)
			(layer "F.CrtYd")
		)
		(fp_poly
			(pts
				(xy -0.9652 -1.778) (xy 0.9652 -1.778) (xy 0.9652 1.778) (xy -0.9652 1.778)
			)
			(stroke
				(width 0)
				(type default)
			)
			(fill no)
			(layer "F.Fab")
		)
		(pad "1" smd rect
			(at 0 -0.9652 180)
			(size 1.397 1.143)
			(layers "F.Cu" "F.Mask" "F.Paste")
			(net "P12V_HDD30")
		)
		(pad "2" smd rect
			(at 0 0.9652 180)
			(size 1.397 1.143)
			(layers "F.Cu" "F.Mask" "F.Paste")
			(net "GND")
		)
	)
	(footprint ""
		(layer "F.Cu")
		(at 475.2848 -263.779 -90)
		(property "Reference" "C173"
			(at 0 0 270)
			(layer "F.SilkS")
			(hide yes)
			(effects
				(font
					(size 1.27 1.27)
				)
			)
		)
		(property "Value" "SC1U16V3KX-5GP"
			(at 0 -2.8194 270)
			(unlocked yes)
			(layer "F.Fab")
			(hide yes)
			(effects
				(font
					(size 1.016 1.016)
					(thickness 0.1524)
				)
			)
		)
		(property "Device Type" "C603H36"
			(at 0 -4.3434 270)
			(unlocked yes)
			(layer "F.Fab")
			(hide yes)
			(effects
				(font
					(size 1.016 1.016)
					(thickness 0.1524)
				)
			)
		)
		(duplicate_pad_numbers_are_jumpers no)
		(fp_line
			(start 0.508 0)
			(end -0.508 0)
			(stroke
				(width 0.2032)
				(type default)
			)
			(layer "F.SilkS")
		)
		(fp_rect
			(start -0.5842 1.3335)
			(end 0.5842 -1.3335)
			(stroke
				(width 0)
				(type default)
			)
			(fill no)
			(layer "F.CrtYd")
		)
		(fp_rect
			(start -0.5842 1.3335)
			(end 0.5842 -1.3335)
			(stroke
				(width 0)
				(type default)
			)
			(fill no)
			(layer "F.Fab")
		)
		(pad "1" smd custom
			(at 0 -0.762 270)
			(size 0.2159 0.2159)
			(layers "F.Cu" "F.Mask" "F.Paste")
			(net "P5V_HDD11")
			(options
				(clearance outline)
				(anchor circle)
			)
			(primitives
				(gr_poly
					(pts
						(arc
							(start -0.3302 -0.4318)
							(mid -0.402042 -0.402042)
							(end -0.4318 -0.3302)
						)
						(arc
							(start -0.4318 0.3302)
							(mid -0.402042 0.402042)
							(end -0.3302 0.4318)
						)
						(arc
							(start 0.3302 0.4318)
							(mid 0.402042 0.402042)
							(end 0.4318 0.3302)
						)
						(arc
							(start 0.4318 -0.3302)
							(mid 0.402042 -0.402042)
							(end 0.3302 -0.4318)
						)
					)
					(width 0)
					(fill yes)
				)
			)
		)
		(pad "2" smd custom
			(at 0 0.762 270)
			(size 0.2159 0.2159)
			(layers "F.Cu" "F.Mask" "F.Paste")
			(net "GND")
			(options
				(clearance outline)
				(anchor circle)
			)
			(primitives
				(gr_poly
					(pts
						(arc
							(start -0.3302 -0.4318)
							(mid -0.402042 -0.402042)
							(end -0.4318 -0.3302)
						)
						(arc
							(start -0.4318 0.3302)
							(mid -0.402042 0.402042)
							(end -0.3302 0.4318)
						)
						(arc
							(start 0.3302 0.4318)
							(mid 0.402042 0.402042)
							(end 0.4318 0.3302)
						)
						(arc
							(start 0.4318 -0.3302)
							(mid 0.402042 -0.402042)
							(end 0.3302 -0.4318)
						)
					)
					(width 0)
					(fill yes)
				)
			)
		)
	)
	(footprint ""
		(layer "F.Cu")
		(at 250.4948 -138.684 180)
		(property "Reference" "R602"
			(at 0 0 180)
			(layer "F.SilkS")
			(hide yes)
			(effects
				(font
					(size 1.27 1.27)
				)
			)
		)
		(property "Value" "2K2R2F-GP"
			(at 0.064008 -3.993896 180)
			(unlocked yes)
			(layer "F.Fab")
			(hide yes)
			(effects
				(font
					(size 1.016 1.016)
					(thickness 0.1524)
				)
			)
		)
		(property "Device Type" "R402H16"
			(at 0.064008 -5.517896 180)
			(unlocked yes)
			(layer "F.Fab")
			(hide yes)
			(effects
				(font
					(size 1.016 1.016)
					(thickness 0.1524)
				)
			)
		)
		(duplicate_pad_numbers_are_jumpers no)
		(fp_line
			(start 0.508 -0.9398)
			(end -0.508 -0.9398)
			(stroke
				(width 0.1524)
				(type default)
			)
			(layer "F.SilkS")
		)
		(fp_line
			(start -0.508 -0.9398)
			(end -0.508 0.9398)
			(stroke
				(width 0.1524)
				(type default)
			)
			(layer "F.SilkS")
		)
		(fp_rect
			(start -0.508 0.9398)
			(end 0.508 -0.9398)
			(stroke
				(width 0)
				(type default)
			)
			(fill no)
			(layer "F.CrtYd")
		)
		(fp_rect
			(start -0.508 0.9398)
			(end 0.508 -0.9398)
			(stroke
				(width 0)
				(type default)
			)
			(fill no)
			(layer "F.Fab")
		)
		(pad "1" smd custom
			(at 0 -0.4445 180)
			(size 0.1397 0.1397)
			(layers "F.Cu" "F.Mask" "F.Paste")
			(net "P3V3_STBY_B")
			(options
				(clearance outline)
				(anchor circle)
			)
			(primitives
				(gr_poly
					(pts
						(arc
							(start -0.1778 -0.2794)
							(mid -0.249642 -0.249642)
							(end -0.2794 -0.1778)
						)
						(arc
							(start -0.2794 0.1778)
							(mid -0.249642 0.249642)
							(end -0.1778 0.2794)
						)
						(arc
							(start 0.1778 0.2794)
							(mid 0.249642 0.249642)
							(end 0.2794 0.1778)
						)
						(arc
							(start 0.2794 -0.1778)
							(mid 0.249642 -0.249642)
							(end 0.1778 -0.2794)
						)
					)
					(width 0)
					(fill yes)
				)
			)
		)
		(pad "2" smd custom
			(at 0 0.4445 180)
			(size 0.1397 0.1397)
			(layers "F.Cu" "F.Mask" "F.Paste")
			(net "I2C_SCC_B_SDA")
			(options
				(clearance outline)
				(anchor circle)
			)
			(primitives
				(gr_poly
					(pts
						(arc
							(start -0.1778 -0.2794)
							(mid -0.249642 -0.249642)
							(end -0.2794 -0.1778)
						)
						(arc
							(start -0.2794 0.1778)
							(mid -0.249642 0.249642)
							(end -0.1778 0.2794)
						)
						(arc
							(start 0.1778 0.2794)
							(mid 0.249642 0.249642)
							(end 0.2794 0.1778)
						)
						(arc
							(start 0.2794 -0.1778)
							(mid 0.249642 -0.249642)
							(end 0.1778 -0.2794)
						)
					)
					(width 0)
					(fill yes)
				)
			)
		)
	)
	(footprint ""
		(layer "F.Cu")
		(at 128.905 -372.237 90)
		(property "Reference" "R936"
			(at 0 0 90)
			(layer "F.SilkS")
			(hide yes)
			(effects
				(font
					(size 1.27 1.27)
				)
			)
		)
		(property "Value" "27KR3F-GP"
			(at -0.0254 -2.5146 90)
			(unlocked yes)
			(layer "F.Fab")
			(hide yes)
			(effects
				(font
					(size 1.016 1.016)
					(thickness 0.1524)
				)
			)
		)
		(property "Device Type" "R603H22"
			(at -0.0254 -4.0386 90)
			(unlocked yes)
			(layer "F.Fab")
			(hide yes)
			(effects
				(font
					(size 1.016 1.016)
					(thickness 0.1524)
				)
			)
		)
		(duplicate_pad_numbers_are_jumpers no)
		(fp_line
			(start 0.2032 0)
			(end 0.4826 0)
			(stroke
				(width 0.2032)
				(type default)
			)
			(layer "F.SilkS")
		)
		(fp_line
			(start -0.4826 0)
			(end -0.2032 0)
			(stroke
				(width 0.2032)
				(type default)
			)
			(layer "F.SilkS")
		)
		(fp_rect
			(start -0.5842 1.3335)
			(end 0.5842 -1.3335)
			(stroke
				(width 0)
				(type default)
			)
			(fill no)
			(layer "F.CrtYd")
		)
		(fp_rect
			(start -0.5842 1.3335)
			(end 0.5842 -1.3335)
			(stroke
				(width 0)
				(type default)
			)
			(fill no)
			(layer "F.Fab")
		)
		(pad "1" smd custom
			(at 0 -0.762 90)
			(size 0.2159 0.2159)
			(layers "F.Cu" "F.Mask" "F.Paste")
			(net "FANTACH_R1")
			(options
				(clearance outline)
				(anchor circle)
			)
			(primitives
				(gr_poly
					(pts
						(arc
							(start -0.3302 -0.4318)
							(mid -0.402042 -0.402042)
							(end -0.4318 -0.3302)
						)
						(arc
							(start -0.4318 0.3302)
							(mid -0.402042 0.402042)
							(end -0.3302 0.4318)
						)
						(arc
							(start 0.3302 0.4318)
							(mid 0.402042 0.402042)
							(end 0.4318 0.3302)
						)
						(arc
							(start 0.4318 -0.3302)
							(mid 0.402042 -0.402042)
							(end 0.3302 -0.4318)
						)
					)
					(width 0)
					(fill yes)
				)
			)
		)
		(pad "2" smd custom
			(at 0 0.762 90)
			(size 0.2159 0.2159)
			(layers "F.Cu" "F.Mask" "F.Paste")
			(net "FAN_1_TACH0")
			(options
				(clearance outline)
				(anchor circle)
			)
			(primitives
				(gr_poly
					(pts
						(arc
							(start -0.3302 -0.4318)
							(mid -0.402042 -0.402042)
							(end -0.4318 -0.3302)
						)
						(arc
							(start -0.4318 0.3302)
							(mid -0.402042 0.402042)
							(end -0.3302 0.4318)
						)
						(arc
							(start 0.3302 0.4318)
							(mid 0.402042 0.402042)
							(end 0.4318 0.3302)
						)
						(arc
							(start 0.4318 -0.3302)
							(mid 0.402042 -0.402042)
							(end 0.3302 -0.4318)
						)
					)
					(width 0)
					(fill yes)
				)
			)
		)
	)
	(footprint ""
		(layer "F.Cu")
		(at 176.657 -265.684 90)
		(property "Reference" "R240"
			(at 0 0 90)
			(layer "F.SilkS")
			(hide yes)
			(effects
				(font
					(size 1.27 1.27)
				)
			)
		)
		(property "Value" "2R6F-GP"
			(at -0.0508 -4.8514 90)
			(unlocked yes)
			(layer "F.Fab")
			(hide yes)
			(effects
				(font
					(size 1.016 1.016)
					(thickness 0.1524)
				)
			)
		)
		(property "Device Type" "R1206H26"
			(at 0 -6.3754 90)
			(unlocked yes)
			(layer "F.Fab")
			(hide yes)
			(effects
				(font
					(size 1.016 1.016)
					(thickness 0.1524)
				)
			)
		)
		(duplicate_pad_numbers_are_jumpers no)
		(fp_line
			(start 1.016 -2.2352)
			(end 1.016 2.2352)
			(stroke
				(width 0.1524)
				(type default)
			)
			(layer "F.SilkS")
		)
		(fp_line
			(start -1.016 -2.2352)
			(end 1.016 -2.2352)
			(stroke
				(width 0.1524)
				(type default)
			)
			(layer "F.SilkS")
		)
		(fp_line
			(start 1.016 2.2352)
			(end -1.016 2.2352)
			(stroke
				(width 0.1524)
				(type default)
			)
			(layer "F.SilkS")
		)
		(fp_line
			(start -1.016 2.2352)
			(end -1.016 -2.2352)
			(stroke
				(width 0.1524)
				(type default)
			)
			(layer "F.SilkS")
		)
		(fp_rect
			(start -1.0922 2.3114)
			(end 1.0922 -2.3114)
			(stroke
				(width 0)
				(type default)
			)
			(fill no)
			(layer "F.CrtYd")
		)
		(fp_poly
			(pts
				(xy -1.0922 -2.3114) (xy 1.0922 -2.3114) (xy 1.0922 2.3114) (xy -1.0922 2.3114)
			)
			(stroke
				(width 0)
				(type default)
			)
			(fill no)
			(layer "F.Fab")
		)
		(pad "1" smd rect
			(at 0 -1.397 90)
			(size 1.651 1.27)
			(layers "F.Cu" "F.Mask" "F.Paste")
			(net "P12V_HDD5")
		)
		(pad "2" smd rect
			(at 0 1.397 90)
			(size 1.651 1.27)
			(layers "F.Cu" "F.Mask" "F.Paste")
			(net "12V_PRE_5")
		)
	)
	(footprint ""
		(layer "F.Cu")
		(at 34.763964 -39.705026)
		(property "Reference" "TP141"
			(at 0 0 0)
			(layer "F.SilkS")
			(hide yes)
			(effects
				(font
					(size 1.27 1.27)
				)
			)
		)
		(property "Value" "*"
			(at -0.0508 -1.6764 0)
			(unlocked yes)
			(layer "F.Fab")
			(hide yes)
			(effects
				(font
					(size 1.016 1.016)
					(thickness 0.1524)
				)
			)
		)
		(property "Device Type" "TPAD32"
			(at -0.0508 -3.2004 0)
			(unlocked yes)
			(layer "F.Fab")
			(hide yes)
			(effects
				(font
					(size 1.016 1.016)
					(thickness 0.1524)
				)
			)
		)
		(duplicate_pad_numbers_are_jumpers no)
		(fp_poly
			(pts
				(arc
					(start 0.4064 0)
					(mid -0.4064 0)
					(end 0.4064 0)
				)
			)
			(stroke
				(width 0)
				(type default)
			)
			(fill no)
			(layer "F.CrtYd")
		)
		(fp_poly
			(pts
				(arc
					(start 0.7112 0)
					(mid -0.7112 0)
					(end 0.7112 0)
				)
			)
			(stroke
				(width 0)
				(type default)
			)
			(fill no)
			(layer "F.Fab")
		)
		(pad "1" smd circle
			(at 0 0)
			(size 0.8128 0.8128)
			(layers "F.Cu" "F.Mask" "F.Paste")
			(net "ACT_HDD_24")
		)
	)
)
